# T6G (Grand Teton) — schematic netlist excerpt (pin names and nets, part order shuffled) for the footprints in the layout excerpt that follows; sources: Cadence DE-HDL packaged netlist, KiCad conversion of 04192023_DAF0TMB3IC0_F0TG_MB_C_brd_V02_OCP.brd

PR6816  Q_RES  0 5% CHIP  pkg 0402LF  page 364 : A = P0V9_RETIMER_CPU1_VRHOT ; B = TP_P0V9_RETIMER_CPU1_VRHOT
C997  Q_CAP  4.7UF 6.3V 20% X6S  pkg 0402  page 312 : A = P1V8_CPU0_RT_1D ; B = GND

(kicad_pcb
	(version 20260206)
	(generator "pcbnew")
	(generator_version "10.0")
	(general
		(thickness 1.6)
		(legacy_teardrops no)
	)
	(paper "A4")
	(title_block
		(title "04192023_DAF0TMB3IC0_F0TG_MB_C_brd_V02_OCP.brd")
		(comment 1 "Grand Teton / footprints 7604-7605 of 8354")
	)
	(layers
		(0 "F.Cu" signal "TOP")
		(4 "In1.Cu" signal "GND")
		(6 "In2.Cu" signal "IN1")
		(8 "In3.Cu" signal "GND1")
		(10 "In4.Cu" signal "IN2")
		(12 "In5.Cu" signal "GND2")
		(14 "In6.Cu" signal "IN3")
		(16 "In7.Cu" signal "GND3")
		(18 "In8.Cu" signal "VCC")
		(20 "In9.Cu" signal "VCC1")
		(22 "In10.Cu" signal "GND4")
		(24 "In11.Cu" signal "IN4")
		(26 "In12.Cu" signal "GND5")
		(28 "In13.Cu" signal "IN5")
		(30 "In14.Cu" signal "GND6")
		(32 "In15.Cu" signal "IN6")
		(34 "In16.Cu" signal "GND7")
		(2 "B.Cu" signal "BOTTOM")
		(9 "F.Adhes" user "F.Adhesive")
		(11 "B.Adhes" user "B.Adhesive")
		(13 "F.Paste" user "Package Geometry/Pastemask Top")
		(15 "B.Paste" user "Package Geometry/Pastemask Bottom")
		(5 "F.SilkS" user "Ref Des/Silkscreen Top")
		(7 "B.SilkS" user "Ref Des/Silkscreen Bottom")
		(1 "F.Mask" user "Board Geometry/Soldermask Top")
		(3 "B.Mask" user "Board Geometry/Soldermask Bottom")
		(17 "Dwgs.User" user "User.Drawings")
		(19 "Cmts.User" user "User.Comments")
		(21 "Eco1.User" user "User.Eco1")
		(23 "Eco2.User" user "User.Eco2")
		(25 "Edge.Cuts" user "Board Geometry/Outline")
		(27 "Margin" user)
		(31 "F.CrtYd" user "Package Geometry/Place Bound Top")
		(29 "B.CrtYd" user "Package Geometry/Place Bound Bottom")
		(35 "F.Fab" user "Ref Des/Assembly Top")
		(33 "B.Fab" user "Ref Des/Assembly Bottom")
	)
	(footprint ""
		(layer "B.Cu")
		(at 395.152372 -395.127988 -90)
		(property "Reference" "C997"
			(at 0 0 90)
			(layer "B.SilkS")
			(hide yes)
			(effects
				(font
					(size 1.27 1.27)
				)
				(justify mirror)
			)
		)
		(property "Value" ""
			(at 0 0 90)
			(layer "B.Fab")
			(effects
				(font
					(size 1.27 1.27)
				)
				(justify mirror)
			)
		)
		(duplicate_pad_numbers_are_jumpers no)
		(fp_line
			(start -0.7874 0.4064)
			(end 0.7874 0.4064)
			(stroke
				(width 0.1524)
				(type default)
			)
			(layer "B.SilkS")
		)
		(fp_line
			(start 0.7874 0.4064)
			(end 0.7874 -0.4064)
			(stroke
				(width 0.1524)
				(type default)
			)
			(layer "B.SilkS")
		)
		(fp_line
			(start -0.7874 -0.4064)
			(end -0.7874 0.4064)
			(stroke
				(width 0.1524)
				(type default)
			)
			(layer "B.SilkS")
		)
		(fp_line
			(start 0.7874 -0.4064)
			(end -0.7874 -0.4064)
			(stroke
				(width 0.1524)
				(type default)
			)
			(layer "B.SilkS")
		)
		(fp_line
			(start -0.67945 0.3048)
			(end -0.120396 0.3048)
			(stroke
				(width 0.1)
				(type default)
			)
			(layer "B.Fab")
		)
		(fp_line
			(start -0.120396 0.3048)
			(end -0.120396 0.2794)
			(stroke
				(width 0.1)
				(type default)
			)
			(layer "B.Fab")
		)
		(fp_line
			(start 0.12065 0.3048)
			(end 0.67945 0.3048)
			(stroke
				(width 0.1)
				(type default)
			)
			(layer "B.Fab")
		)
		(fp_line
			(start 0.67945 0.3048)
			(end 0.67945 -0.305054)
			(stroke
				(width 0.1)
				(type default)
			)
			(layer "B.Fab")
		)
		(fp_line
			(start -0.120396 0.2794)
			(end 0.12065 0.2794)
			(stroke
				(width 0.1)
				(type default)
			)
			(layer "B.Fab")
		)
		(fp_line
			(start 0.12065 0.2794)
			(end 0.12065 0.3048)
			(stroke
				(width 0.1)
				(type default)
			)
			(layer "B.Fab")
		)
		(fp_line
			(start -0.12065 -0.2794)
			(end -0.12065 -0.3048)
			(stroke
				(width 0.1)
				(type default)
			)
			(layer "B.Fab")
		)
		(fp_line
			(start 0.12065 -0.2794)
			(end -0.12065 -0.2794)
			(stroke
				(width 0.1)
				(type default)
			)
			(layer "B.Fab")
		)
		(fp_line
			(start -0.67945 -0.3048)
			(end -0.67945 0.3048)
			(stroke
				(width 0.1)
				(type default)
			)
			(layer "B.Fab")
		)
		(fp_line
			(start -0.12065 -0.3048)
			(end -0.67945 -0.3048)
			(stroke
				(width 0.1)
				(type default)
			)
			(layer "B.Fab")
		)
		(fp_line
			(start 0.12065 -0.305054)
			(end 0.12065 -0.2794)
			(stroke
				(width 0.1)
				(type default)
			)
			(layer "B.Fab")
		)
		(fp_line
			(start 0.67945 -0.305054)
			(end 0.12065 -0.305054)
			(stroke
				(width 0.1)
				(type default)
			)
			(layer "B.Fab")
		)
		(pad "1" smd circle
			(at 0.40005 0 90)
			(size 0 0)
			(layers "B.Cu" "B.Mask" "B.Paste")
			(net "P1V8_CPU0_RT_1D")
		)
		(pad "2" smd circle
			(at -0.40005 0 90)
			(size 0 0)
			(layers "B.Cu" "B.Mask" "B.Paste")
			(net "GND")
		)
	)
	(footprint ""
		(layer "B.Cu")
		(at 19.727418 -409.04287 90)
		(property "Reference" "PR6816"
			(at 0 0 90)
			(layer "B.SilkS")
			(hide yes)
			(effects
				(font
					(size 1.27 1.27)
				)
				(justify mirror)
			)
		)
		(property "Value" ""
			(at 0 0 90)
			(layer "B.Fab")
			(effects
				(font
					(size 1.27 1.27)
				)
				(justify mirror)
			)
		)
		(duplicate_pad_numbers_are_jumpers no)
		(fp_line
			(start 0.7874 -0.4064)
			(end -0.7874 -0.4064)
			(stroke
				(width 0.1524)
				(type default)
			)
			(layer "B.SilkS")
		)
		(fp_line
			(start -0.7874 -0.4064)
			(end -0.7874 0.4064)
			(stroke
				(width 0.1524)
				(type default)
			)
			(layer "B.SilkS")
		)
		(fp_line
			(start 0.7874 0.4064)
			(end 0.7874 -0.4064)
			(stroke
				(width 0.1524)
				(type default)
			)
			(layer "B.SilkS")
		)
		(fp_line
			(start -0.7874 0.4064)
			(end 0.7874 0.4064)
			(stroke
				(width 0.1524)
				(type default)
			)
			(layer "B.SilkS")
		)
		(fp_line
			(start 0.67945 -0.305054)
			(end 0.12065 -0.305054)
			(stroke
				(width 0.1)
				(type default)
			)
			(layer "B.Fab")
		)
		(fp_line
			(start 0.12065 -0.305054)
			(end 0.12065 -0.2794)
			(stroke
				(width 0.1)
				(type default)
			)
			(layer "B.Fab")
		)
		(fp_line
			(start -0.12065 -0.3048)
			(end -0.67945 -0.3048)
			(stroke
				(width 0.1)
				(type default)
			)
			(layer "B.Fab")
		)
		(fp_line
			(start -0.67945 -0.3048)
			(end -0.67945 0.3048)
			(stroke
				(width 0.1)
				(type default)
			)
			(layer "B.Fab")
		)
		(fp_line
			(start 0.12065 -0.2794)
			(end -0.12065 -0.2794)
			(stroke
				(width 0.1)
				(type default)
			)
			(layer "B.Fab")
		)
		(fp_line
			(start -0.12065 -0.2794)
			(end -0.12065 -0.3048)
			(stroke
				(width 0.1)
				(type default)
			)
			(layer "B.Fab")
		)
		(fp_line
			(start 0.12065 0.2794)
			(end 0.12065 0.3048)
			(stroke
				(width 0.1)
				(type default)
			)
			(layer "B.Fab")
		)
		(fp_line
			(start -0.120396 0.2794)
			(end 0.12065 0.2794)
			(stroke
				(width 0.1)
				(type default)
			)
			(layer "B.Fab")
		)
		(fp_line
			(start 0.67945 0.3048)
			(end 0.67945 -0.305054)
			(stroke
				(width 0.1)
				(type default)
			)
			(layer "B.Fab")
		)
		(fp_line
			(start 0.12065 0.3048)
			(end 0.67945 0.3048)
			(stroke
				(width 0.1)
				(type default)
			)
			(layer "B.Fab")
		)
		(fp_line
			(start -0.120396 0.3048)
			(end -0.120396 0.2794)
			(stroke
				(width 0.1)
				(type default)
			)
			(layer "B.Fab")
		)
		(fp_line
			(start -0.67945 0.3048)
			(end -0.120396 0.3048)
			(stroke
				(width 0.1)
				(type default)
			)
			(layer "B.Fab")
		)
		(pad "1" smd circle
			(at 0.40005 0 270)
			(size 0 0)
			(layers "B.Cu" "B.Mask" "B.Paste")
			(net "P0V9_RETIMER_CPU1_VRHOT")
		)
		(pad "2" smd circle
			(at -0.40005 0 270)
			(size 0 0)
			(layers "B.Cu" "B.Mask" "B.Paste")
			(net "TP_P0V9_RETIMER_CPU1_VRHOT")
		)
	)
)
